# BASEBOARD_FAB2 (Tioga Pass) — schematic netlist excerpt (pin names and nets, part order shuffled) for the footprints in the layout excerpt that follows; sources: Cadence DE-HDL packaged netlist, KiCad conversion of Wiwynn_Tioga_Pass_MB.brd

R6P16  RES  1.00K 1% CHIP  pkg 0402  page 201 : A = PVCCIO_CPU0 ; B = VR_PVCCIN_CPU0_VREN

R9R1  RES_PWR  0.001 1% CHIP  pkg 6PAD  page 200
  \1\  = P12V_PSU
  \2\  = P12V_MB0_SW
  \3\  = P12V_HSC_SENP1
  \4\  = P12V_HSC_SENN1
  \5\  = P12V_PSU
  \6\  = P12V_MB0_SW

(kicad_pcb
	(version 20260206)
	(generator "pcbnew")
	(generator_version "10.0")
	(general
		(thickness 1.6)
		(legacy_teardrops no)
	)
	(paper "A4")
	(title_block
		(title "Wiwynn_Tioga_Pass_MB.brd")
		(comment 1 "Tioga Pass / footprints 4559-4560 of 4770")
	)
	(layers
		(0 "F.Cu" signal "TOP")
		(4 "In1.Cu" signal "L2GND")
		(6 "In2.Cu" signal "L3")
		(8 "In3.Cu" signal "L4GND")
		(10 "In4.Cu" signal "L5")
		(12 "In5.Cu" signal "L6GND")
		(14 "In6.Cu" signal "L7VCC")
		(16 "In7.Cu" signal "L8VCC")
		(18 "In8.Cu" signal "L9GND")
		(20 "In9.Cu" signal "L10")
		(22 "In10.Cu" signal "L11GND")
		(24 "In11.Cu" signal "L12")
		(26 "In12.Cu" signal "L13GND")
		(2 "B.Cu" signal "BOTTOM")
		(9 "F.Adhes" user "F.Adhesive")
		(11 "B.Adhes" user "B.Adhesive")
		(13 "F.Paste" user "Package Geometry/Pastemask Top")
		(15 "B.Paste" user "Package Geometry/Pastemask Bottom")
		(5 "F.SilkS" user "Ref Des/Silkscreen Top")
		(7 "B.SilkS" user "Ref Des/Silkscreen Bottom")
		(1 "F.Mask" user "Board Geometry/Soldermask Top")
		(3 "B.Mask" user "Board Geometry/Soldermask Bottom")
		(17 "Dwgs.User" user "User.Drawings")
		(19 "Cmts.User" user "User.Comments")
		(21 "Eco1.User" user "User.Eco1")
		(23 "Eco2.User" user "User.Eco2")
		(25 "Edge.Cuts" user "Board Geometry/Outline")
		(27 "Margin" user)
		(31 "F.CrtYd" user "Package Geometry/Place Bound Top")
		(29 "B.CrtYd" user "Package Geometry/Place Bound Bottom")
		(35 "F.Fab" user "Ref Des/Assembly Top")
		(33 "B.Fab" user "Ref Des/Assembly Bottom")
	)
	(footprint ""
		(layer "B.Cu")
		(at 7.366 -63.56604 180)
		(property "Reference" "R9R1"
			(at -4.191 -1.48971 0)
			(unlocked yes)
			(layer "B.SilkS")
			(effects
				(font
					(size 0.7874 0.5842)
					(thickness 0.1524)
				)
				(justify left mirror)
			)
		)
		(property "Value" ""
			(at 0 0 0)
			(layer "B.Fab")
			(effects
				(font
					(size 1.27 1.27)
				)
				(justify mirror)
			)
		)
		(duplicate_pad_numbers_are_jumpers no)
		(fp_circle
			(center 2.29362 -0.691642)
			(end 2.16662 -0.691642)
			(stroke
				(width 0.254)
				(type default)
			)
			(fill no)
			(layer "B.SilkS")
		)
		(fp_rect
			(start 0.8001 3.11658)
			(end -5.8039 -0.31242)
			(stroke
				(width 0)
				(type default)
			)
			(fill no)
			(layer "B.CrtYd")
		)
		(fp_line
			(start 0.8001 3.11658)
			(end 0.8001 -0.31242)
			(stroke
				(width 0.1)
				(type default)
			)
			(layer "B.Fab")
		)
		(fp_line
			(start 0.8001 -0.31242)
			(end -5.8039 -0.31242)
			(stroke
				(width 0.1)
				(type default)
			)
			(layer "B.Fab")
		)
		(fp_line
			(start -5.8039 3.11658)
			(end 0.8001 3.11658)
			(stroke
				(width 0.1)
				(type default)
			)
			(layer "B.Fab")
		)
		(fp_line
			(start -5.8039 -0.31242)
			(end -5.8039 3.11658)
			(stroke
				(width 0.1)
				(type default)
			)
			(layer "B.Fab")
		)
		(fp_circle
			(center 1.740916 -1.623822)
			(end 1.613916 -1.623822)
			(stroke
				(width 0.254)
				(type default)
			)
			(fill no)
			(layer "B.Fab")
		)
		(pad "1" smd rect
			(at 0 0)
			(size 3.4036 1.1938)
			(layers "B.Cu" "B.Mask" "B.Paste")
			(net "P12V_PSU")
		)
		(pad "2" smd rect
			(at -5.0038 0)
			(size 3.4036 1.1938)
			(layers "B.Cu" "B.Mask" "B.Paste")
			(net "P12V_MB0_SW")
		)
		(pad "3" smd rect
			(at 0 1.40208)
			(size 3.4036 0.6096)
			(layers "B.Cu" "B.Mask" "B.Paste")
			(net "P12V_HSC_SENP1")
		)
		(pad "4" smd rect
			(at -5.0038 1.40208)
			(size 3.4036 0.6096)
			(layers "B.Cu" "B.Mask" "B.Paste")
			(net "P12V_HSC_SENN1")
		)
		(pad "5" smd rect
			(at 0 2.80416)
			(size 3.4036 1.1938)
			(layers "B.Cu" "B.Mask" "B.Paste")
			(net "P12V_PSU")
		)
		(pad "6" smd rect
			(at -5.0038 2.80416)
			(size 3.4036 1.1938)
			(layers "B.Cu" "B.Mask" "B.Paste")
			(net "P12V_MB0_SW")
		)
		(zone
			(layer "B.Cu")
			(hatch none 0.5)
			(connect_pads
				(clearance 0)
			)
			(min_thickness 0.25)
			(keepout
				(tracks allowed)
				(vias not_allowed)
				(pads allowed)
				(copperpour not_allowed)
				(footprints allowed)
			)
			(placement
				(enabled no)
				(sheetname "")
			)
			(fill
				(thermal_gap 0.5)
				(thermal_bridge_width 0.5)
				(island_removal_mode 0)
			)
			(polygon
				(pts
					(xy 9.0678 -63.17996) (xy 9.0678 -66.9671) (xy 10.668 -66.9671) (xy 10.668 -62.96914) (xy 9.11352 -62.96914)
					(xy 9.0678 -62.96914)
				)
			)
		)
	)
	(footprint ""
		(layer "B.Cu")
		(at 181.0004 -77.1144 -90)
		(property "Reference" "R6P16"
			(at 0 0 90)
			(layer "B.SilkS")
			(hide yes)
			(effects
				(font
					(size 1.27 1.27)
				)
				(justify mirror)
			)
		)
		(property "Value" ""
			(at 0 0 90)
			(layer "B.Fab")
			(effects
				(font
					(size 1.27 1.27)
				)
				(justify mirror)
			)
		)
		(duplicate_pad_numbers_are_jumpers no)
		(fp_poly
			(pts
				(xy 0.2794 -0.1016) (xy -0.2794 -0.1016) (xy -0.2794 0.9906) (xy 0.2794 0.9906)
			)
			(stroke
				(width 0)
				(type default)
			)
			(fill no)
			(layer "B.CrtYd")
		)
		(fp_line
			(start -0.2794 0.9906)
			(end -0.2794 -0.1016)
			(stroke
				(width 0.1)
				(type default)
			)
			(layer "B.Fab")
		)
		(fp_line
			(start 0.2794 0.9906)
			(end -0.2794 0.9906)
			(stroke
				(width 0.1)
				(type default)
			)
			(layer "B.Fab")
		)
		(fp_line
			(start -0.2794 -0.1016)
			(end 0.2794 -0.1016)
			(stroke
				(width 0.1)
				(type default)
			)
			(layer "B.Fab")
		)
		(fp_line
			(start 0.2794 -0.1016)
			(end 0.2794 0.9906)
			(stroke
				(width 0.1)
				(type default)
			)
			(layer "B.Fab")
		)
		(pad "1" smd rect
			(at 0 0 90)
			(size 0.508 0.508)
			(layers "B.Cu" "B.Mask" "B.Paste")
			(net "PVCCIO_CPU0")
		)
		(pad "2" smd rect
			(at 0 0.889 90)
			(size 0.508 0.508)
			(layers "B.Cu" "B.Mask" "B.Paste")
			(net "VR_PVCCIN_CPU0_VREN")
		)
		(zone
			(layer "B.Cu")
			(hatch none 0.5)
			(connect_pads
				(clearance 0)
			)
			(min_thickness 0.25)
			(keepout
				(tracks not_allowed)
				(vias allowed)
				(pads allowed)
				(copperpour not_allowed)
				(footprints allowed)
			)
			(placement
				(enabled no)
				(sheetname "")
			)
			(fill
				(thermal_gap 0.5)
				(thermal_bridge_width 0.5)
				(island_removal_mode 0)
			)
			(polygon
				(pts
					(xy 180.3654 -76.8604) (xy 180.3654 -77.3684) (xy 180.7464 -77.3684) (xy 180.7464 -76.8604)
				)
			)
		)
		(zone
			(layer "B.Cu")
			(hatch none 0.5)
			(connect_pads
				(clearance 0)
			)
			(min_thickness 0.25)
			(keepout
				(tracks allowed)
				(vias not_allowed)
				(pads allowed)
				(copperpour not_allowed)
				(footprints allowed)
			)
			(placement
				(enabled no)
				(sheetname "")
			)
			(fill
				(thermal_gap 0.5)
				(thermal_bridge_width 0.5)
				(island_removal_mode 0)
			)
			(polygon
				(pts
					(xy 180.7464 -76.8604) (xy 180.7464 -77.3684) (xy 180.3654 -77.3684) (xy 180.3654 -76.8604)
				)
			)
		)
	)
)
